M48
INCH,TZ
T01C.01
T02C.012
T03C.016
T04C.032
T05C.035
T06C.039
T07C.045
T08C.061
T09C.062
T010C.079
T011C.099
T012C.14
T013C.158
T014C.197
;EXTENTS: -99.880 -70.461 240.968 134.177 
;LEADER: 12 
;HEADER: 
;CODE  : ASCII 
;FILE  : 12004-1.rou for board 12004-1.brd
%
G90
F1
M16
G40
M30
